# T6G (Grand Teton) — schematic netlist excerpt (pin names and nets, part order shuffled) for the footprints in the layout excerpt that follows; sources: Cadence DE-HDL packaged netlist, KiCad conversion of 04192023_DAF0TMB3IC0_F0TG_MB_C_brd_V02_OCP.brd

C6074  Q_CAP  0.01UF 50V 10% X7R  pkg C0402  page 177 : A = P1V2_AUX ; B = GND
C1176  Q_CAP  0.1UF 16V 10% X7R  pkg C0402  page 83 : A = P3V3_AUX ; B = GND

(kicad_pcb
	(version 20260206)
	(generator "pcbnew")
	(generator_version "10.0")
	(general
		(thickness 1.6)
		(legacy_teardrops no)
	)
	(paper "A4")
	(title_block
		(title "04192023_DAF0TMB3IC0_F0TG_MB_C_brd_V02_OCP.brd")
		(comment 1 "Grand Teton / footprints 5774-5775 of 8354")
	)
	(layers
		(0 "F.Cu" signal "TOP")
		(4 "In1.Cu" signal "GND")
		(6 "In2.Cu" signal "IN1")
		(8 "In3.Cu" signal "GND1")
		(10 "In4.Cu" signal "IN2")
		(12 "In5.Cu" signal "GND2")
		(14 "In6.Cu" signal "IN3")
		(16 "In7.Cu" signal "GND3")
		(18 "In8.Cu" signal "VCC")
		(20 "In9.Cu" signal "VCC1")
		(22 "In10.Cu" signal "GND4")
		(24 "In11.Cu" signal "IN4")
		(26 "In12.Cu" signal "GND5")
		(28 "In13.Cu" signal "IN5")
		(30 "In14.Cu" signal "GND6")
		(32 "In15.Cu" signal "IN6")
		(34 "In16.Cu" signal "GND7")
		(2 "B.Cu" signal "BOTTOM")
		(9 "F.Adhes" user "F.Adhesive")
		(11 "B.Adhes" user "B.Adhesive")
		(13 "F.Paste" user "Package Geometry/Pastemask Top")
		(15 "B.Paste" user "Package Geometry/Pastemask Bottom")
		(5 "F.SilkS" user "Ref Des/Silkscreen Top")
		(7 "B.SilkS" user "Ref Des/Silkscreen Bottom")
		(1 "F.Mask" user "Board Geometry/Soldermask Top")
		(3 "B.Mask" user "Board Geometry/Soldermask Bottom")
		(17 "Dwgs.User" user "User.Drawings")
		(19 "Cmts.User" user "User.Comments")
		(21 "Eco1.User" user "User.Eco1")
		(23 "Eco2.User" user "User.Eco2")
		(25 "Edge.Cuts" user "Board Geometry/Outline")
		(27 "Margin" user)
		(31 "F.CrtYd" user "Package Geometry/Place Bound Top")
		(29 "B.CrtYd" user "Package Geometry/Place Bound Bottom")
		(35 "F.Fab" user "Ref Des/Assembly Top")
		(33 "B.Fab" user "Ref Des/Assembly Bottom")
	)
	(footprint ""
		(layer "B.Cu")
		(at 126.375668 -37.47643)
		(property "Reference" "C6074"
			(at 0 0 0)
			(layer "B.SilkS")
			(hide yes)
			(effects
				(font
					(size 1.27 1.27)
				)
				(justify mirror)
			)
		)
		(property "Value" ""
			(at 0 0 0)
			(layer "B.Fab")
			(effects
				(font
					(size 1.27 1.27)
				)
				(justify mirror)
			)
		)
		(duplicate_pad_numbers_are_jumpers no)
		(fp_line
			(start -0.7874 -0.4064)
			(end -0.7874 0.4064)
			(stroke
				(width 0.1524)
				(type default)
			)
			(layer "B.SilkS")
		)
		(fp_line
			(start -0.7874 0.4064)
			(end 0.7874 0.4064)
			(stroke
				(width 0.1524)
				(type default)
			)
			(layer "B.SilkS")
		)
		(fp_line
			(start 0.7874 -0.4064)
			(end -0.7874 -0.4064)
			(stroke
				(width 0.1524)
				(type default)
			)
			(layer "B.SilkS")
		)
		(fp_line
			(start 0.7874 0.4064)
			(end 0.7874 -0.4064)
			(stroke
				(width 0.1524)
				(type default)
			)
			(layer "B.SilkS")
		)
		(fp_line
			(start -0.67945 -0.3048)
			(end -0.67945 0.3048)
			(stroke
				(width 0.1)
				(type default)
			)
			(layer "B.Fab")
		)
		(fp_line
			(start -0.67945 0.3048)
			(end -0.120396 0.3048)
			(stroke
				(width 0.1)
				(type default)
			)
			(layer "B.Fab")
		)
		(fp_line
			(start -0.12065 -0.3048)
			(end -0.67945 -0.3048)
			(stroke
				(width 0.1)
				(type default)
			)
			(layer "B.Fab")
		)
		(fp_line
			(start -0.12065 -0.2794)
			(end -0.12065 -0.3048)
			(stroke
				(width 0.1)
				(type default)
			)
			(layer "B.Fab")
		)
		(fp_line
			(start -0.120396 0.2794)
			(end 0.12065 0.2794)
			(stroke
				(width 0.1)
				(type default)
			)
			(layer "B.Fab")
		)
		(fp_line
			(start -0.120396 0.3048)
			(end -0.120396 0.2794)
			(stroke
				(width 0.1)
				(type default)
			)
			(layer "B.Fab")
		)
		(fp_line
			(start 0.12065 -0.305054)
			(end 0.12065 -0.2794)
			(stroke
				(width 0.1)
				(type default)
			)
			(layer "B.Fab")
		)
		(fp_line
			(start 0.12065 -0.2794)
			(end -0.12065 -0.2794)
			(stroke
				(width 0.1)
				(type default)
			)
			(layer "B.Fab")
		)
		(fp_line
			(start 0.12065 0.2794)
			(end 0.12065 0.3048)
			(stroke
				(width 0.1)
				(type default)
			)
			(layer "B.Fab")
		)
		(fp_line
			(start 0.12065 0.3048)
			(end 0.67945 0.3048)
			(stroke
				(width 0.1)
				(type default)
			)
			(layer "B.Fab")
		)
		(fp_line
			(start 0.67945 -0.305054)
			(end 0.12065 -0.305054)
			(stroke
				(width 0.1)
				(type default)
			)
			(layer "B.Fab")
		)
		(fp_line
			(start 0.67945 0.3048)
			(end 0.67945 -0.305054)
			(stroke
				(width 0.1)
				(type default)
			)
			(layer "B.Fab")
		)
		(pad "1" smd circle
			(at 0.40005 0 180)
			(size 0 0)
			(layers "B.Cu" "B.Mask" "B.Paste")
			(net "P1V2_AUX")
		)
		(pad "2" smd circle
			(at -0.40005 0 180)
			(size 0 0)
			(layers "B.Cu" "B.Mask" "B.Paste")
			(net "GND")
		)
	)
	(footprint ""
		(layer "B.Cu")
		(at 183.932322 -115.022376)
		(property "Reference" "C1176"
			(at 0 0 0)
			(layer "B.SilkS")
			(hide yes)
			(effects
				(font
					(size 1.27 1.27)
				)
				(justify mirror)
			)
		)
		(property "Value" ""
			(at 0 0 0)
			(layer "B.Fab")
			(effects
				(font
					(size 1.27 1.27)
				)
				(justify mirror)
			)
		)
		(duplicate_pad_numbers_are_jumpers no)
		(fp_line
			(start -0.69215 -0.2921)
			(end -0.69215 0.2921)
			(stroke
				(width 0.1524)
				(type default)
			)
			(layer "B.SilkS")
		)
		(fp_line
			(start -0.69215 0.2921)
			(end 0.69215 0.2921)
			(stroke
				(width 0.1524)
				(type default)
			)
			(layer "B.SilkS")
		)
		(fp_line
			(start 0.69215 -0.2921)
			(end -0.69215 -0.2921)
			(stroke
				(width 0.1524)
				(type default)
			)
			(layer "B.SilkS")
		)
		(fp_line
			(start 0.69215 0.2921)
			(end 0.69215 -0.2921)
			(stroke
				(width 0.1524)
				(type default)
			)
			(layer "B.SilkS")
		)
		(fp_line
			(start -0.51435 -0.2794)
			(end -0.51435 0.2794)
			(stroke
				(width 0.1)
				(type default)
			)
			(layer "B.Fab")
		)
		(fp_line
			(start -0.51435 0.2794)
			(end 0.51435 0.2794)
			(stroke
				(width 0.1)
				(type default)
			)
			(layer "B.Fab")
		)
		(fp_line
			(start 0.51435 -0.2794)
			(end -0.51435 -0.2794)
			(stroke
				(width 0.1)
				(type default)
			)
			(layer "B.Fab")
		)
		(fp_line
			(start 0.51435 0.2794)
			(end 0.51435 -0.2794)
			(stroke
				(width 0.1)
				(type default)
			)
			(layer "B.Fab")
		)
		(pad "1" smd circle
			(at 0.40005 0 180)
			(size 0 0)
			(layers "B.Cu" "B.Mask" "B.Paste")
			(net "P3V3_AUX")
		)
		(pad "2" smd circle
			(at -0.40005 0 180)
			(size 0 0)
			(layers "B.Cu" "B.Mask" "B.Paste")
			(net "GND")
		)
		(zone
			(layer "B.Cu")
			(hatch none 0.5)
			(connect_pads
				(clearance 0)
			)
			(min_thickness 0.25)
			(keepout
				(tracks not_allowed)
				(vias allowed)
				(pads allowed)
				(copperpour not_allowed)
				(footprints allowed)
			)
			(placement
				(enabled no)
				(sheetname "")
			)
			(fill
				(thermal_gap 0.5)
				(thermal_bridge_width 0.5)
				(island_removal_mode 0)
			)
			(polygon
				(pts
					(xy 183.741822 -114.934746) (xy 183.741822 -115.110006) (xy 183.831992 -115.168426) (xy 184.031382 -115.168426)
					(xy 184.122822 -115.11026) (xy 184.122822 -114.934746) (xy 184.031382 -114.87658) (xy 183.831992 -114.87658)
				)
			)
		)
	)
)
